FILE_TYPE = CONNECTIVITY;
{Allegro Design Entry HDL 17.2-2016 S081 (4005846) 1/11/2022}
"PAGE_NUMBER" = 23;
0"NC";
1"CRT_VCC5\g";
2"P3V3_RGM\g";
3"P3V3_RGM\g";
4"CRT_VCC5\g";
5"P5V_AUX\g";
6"P5V_AUX\g";
7"P5V_AUX\g";
8"CRT_VCC5\g";
9"P5V_AUX\g";
10"CRT_VCC5\g";
11"CRT_VCC5\g";
12"GND\g";
13"GND\g";
14"GND\g";
15"GND\g";
16"GND\g";
17"GND\g";
18"GND\g";
19"GND\g";
20"GND\g";
21"GND\g";
22"GND\g";
23"GND\g";
24"V_VGAVS_BUF_R";
25"BMC_DDC_BUF_EN";
26"V_BMC_LS_DDC_SCL";
27"V_BMC_LS_DDC_SDA_R";
28"V_VGAHS_BUF";
29"V_VGAHS_BUF_R";
30"V_VGAVS_BUF";
31"V_DACB_IO";
32"V_DACR_IO";
33"V_DACG_IO";
34"V_BMC_DDC_LS_GATE";
35"BMC_DDC_BUF_PWR";
36"V_BMC_LS_DDC_SCL_R";
37"V_DACB";
38"V_VGAHS";
39"V_BMC_LS_DDC_SDA";
40"V_VGAVS";
41"V_DACG";
42"V_DACR";
43"V_BMC_LS_DDC_SDA";
44"V_BMC_LS_DDC_SCL";
45"V_BMC_DDC_SCL";
46"V_DACR_IO";
47"V_DACG_IO";
48"V_DACB_IO";
49"V_VGAVS_BUF";
50"V_VGAHS_BUF";
51"V_BMC_LS_DDC_SDA_R";
52"V_BMC_LS_DDC_SCL_R";
53"CRT_VCC5_2_FUSE";
54"CRT_VCC5_2_D";
55"V_BMC_DDC_SDA";
56"TP4";
57"TP_ESD_VGA_P4";
%"UNIVERSAL_GND"
"1","(-2100,275)","0","logical_power","I10";
;
HDL_POWER"GND"
CDS_LIB"logical_power";
"A"17;
%"Q_CAP"
"1","(-2100,575)","0","pure_quanta","I11";
;
MATERIAL"X7R"
VOLTAGE"25V"
VALUE"0.1UF"
PACK_TYPE"0402"
TOLERANCE"10%"
PART_NUMBER"CH4104K1B00"
CDS_LIB"pure_quanta"
LOCATION"C202"
$SEC"1"
CDS_SEC"1";
"B"
$PN"2"17;
"A"
$PN"1"6;
%"Q_CAP"
"1","(-1875,575)","0","pure_quanta","I12";
;
MATERIAL"X7R"
TOLERANCE"10%"
VOLTAGE"25V"
PACK_TYPE"0402"
VALUE"0.1UF"
PART_NUMBER"CH4104K1B00"
CDS_LIB"pure_quanta"
LOCATION"C203"
$SEC"1"
CDS_SEC"1";
"B"
$PN"2"17;
"A"
$PN"1"6;
%"UNIVERSAL_POWER"
"1","(-2100,900)","0","logical_power","I13";
;
HDL_POWER"P5V_AUX"
CDS_LIB"logical_power";
"A"6;
%"UNIVERSAL_GND"
"1","(5950,-1025)","0","logical_power","I150";
;
HDL_POWER"GND"
CDS_LIB"logical_power";
"A"23;
%"Q_FUSE"
"1","(4400,-775)","0","pure_quanta","I153";
;
PACK_TYPE"SMLF"
VALUE"1.1A/8V"
MATERIAL"EMPTY"
PART_NUMBER"DK110TPU003"
NEEDS_NO_SIZE"TRUE"
CDS_LIB"pure_quanta"
SEC_TYPE"SMLF"
LOCATION"FS1"
SEC"1";
"2 \B"
$PN"2"53;
"1 \B"
$PN"1"54;
%"UNIVERSAL_POWER"
"1","(3050,-475)","0","logical_power","I154";
;
HDL_POWER"P5V_AUX"
CDS_LIB"logical_power";
"A"9;
%"DT1240E04LP7"
"1","(3300,4000)","0","pure_quanta","I155";
;
PART_NUMBER"BC001240Z01"
PART_TYPE"SMLF"
VALUE"DT1240E-04LP-7"
MATERIAL"IC"
CDS_LMAN_SYM_OUTLINE"-250,400,250,-400"
NEEDS_NO_SIZE"TRUE"
CDS_LIB"pure_quanta"
LOCATION"U35"
$SEC"1"
CDS_SEC"1";
"NC2"
$PN"7"32;
"IO4"
$PN"5"56;
"IO2"
$PN"2"33;
"NC4"
$PN"10"31;
"NC3"
$PN"9"33;
"VSS2"
$PN"8"12;
"NC1"
$PN"6"57;
"IO3"
$PN"4"32;
"VSS1"
$PN"3"12;
"IO1"
$PN"1"31;
%"DT1240E04LP7"
"1","(1550,4000)","0","pure_quanta","I156";
;
PART_NUMBER"BC001240Z01"
VALUE"DT1240E-04LP-7"
MATERIAL"IC"
PART_TYPE"SMLF"
NEEDS_NO_SIZE"TRUE"
CDS_LMAN_SYM_OUTLINE"-250,400,250,-400"
CDS_LIB"pure_quanta"
LOCATION"U34"
$SEC"1"
CDS_SEC"1";
"NC2"
$PN"7"28;
"IO4"
$PN"5"30;
"IO2"
$PN"2"27;
"NC4"
$PN"10"36;
"NC3"
$PN"9"27;
"VSS2"
$PN"8"13;
"NC1"
$PN"6"30;
"IO3"
$PN"4"28;
"VSS1"
$PN"3"13;
"IO1"
$PN"1"36;
%"UNIVERSAL_GND"
"1","(2050,4000)","0","logical_power","I157";
;
CDS_LIB"logical_power"
HDL_POWER"GND";
"A"13;
%"UNIVERSAL_GND"
"1","(3800,4000)","0","logical_power","I158";
;
HDL_POWER"GND"
CDS_LIB"logical_power";
"A"12;
%"SCHOTTKY_12"
"1","(3425,-775)","0","pure_quanta","I161";
;
VALUE"SBA130Q"
PART_TYPE"SMLF"
PART_NUMBER"BCSBA130Z00"
MATERIAL"EMPTY"
CDS_LIB"pure_quanta"
NEEDS_NO_SIZE"TRUE"
CDS_LMAN_SYM_OUTLINE"-75,50,75,-50"
LOCATION"D16"
$SEC"1"
CDS_SEC"1";
"C"
$PN"2"54;
"A"
$PN"1"9;
%"SCONN13_502280130CV01"
"1","(6250,-550)","2","pure_quanta","I165";
;
VALUE"SCONN13_50228-0130C-V01"
PART_TYPE"SMLF"
MATERIAL"IO"
PART_NUMBER"DFHD13MS080"
CDS_LIB"pure_quanta"
NEEDS_NO_SIZE"TRUE"
CDS_LMAN_SYM_OUTLINE"-75,425,75,-425"
LOCATION"J8"
$SEC"1"
CDS_SEC"1";
"G2"
$PN"G2"23;
"G1"
$PN"G1"23;
"13"
$PN"13"53;
"12"
$PN"12"52;
"11"
$PN"11"51;
"10"
$PN"10"23;
"9"
$PN"9"50;
"8"
$PN"8"23;
"7"
$PN"7"49;
"6"
$PN"6"23;
"5"
$PN"5"48;
"4"
$PN"4"23;
"3"
$PN"3"47;
"2"
$PN"2"23;
"1"
$PN"1"46;
%"Q_INDUCTOR"
"1","(-75,2025)","0","pure_quanta","I166";
;
MATERIAL"IND"
PACK_TYPE"SMLF"
PART_NUMBER"CX8BB470007"
VALUE"BLM18BB470/500MA"
NEEDS_NO_SIZE"TRUE"
CDS_LIB"pure_quanta"
LOCATION"L28"
$SEC"1"
CDS_SEC"1";
"1"
$PN"1"37;
"2"
$PN"2"31;
%"Q_INDUCTOR"
"1","(-75,1725)","0","pure_quanta","I167";
;
MATERIAL"IND"
PART_NUMBER"CX8BB470007"
PACK_TYPE"SMLF"
VALUE"BLM18BB470/500MA"
CDS_LIB"pure_quanta"
NEEDS_NO_SIZE"TRUE"
LOCATION"L29"
$SEC"1"
CDS_SEC"1";
"1"
$PN"1"41;
"2"
$PN"2"33;
%"Q_INDUCTOR"
"1","(-75,1425)","0","pure_quanta","I168";
;
PACK_TYPE"SMLF"
MATERIAL"IND"
PART_NUMBER"CX8BB470007"
VALUE"BLM18BB470/500MA"
CDS_LIB"pure_quanta"
NEEDS_NO_SIZE"TRUE"
LOCATION"L30"
$SEC"1"
CDS_SEC"1";
"1"
$PN"1"42;
"2"
$PN"2"32;
%"Q_CAP"
"1","(175,1100)","0","pure_quanta","I169";
;
VOLTAGE"50V"
TOLERANCE"5%"
MATERIAL"NPO"
PACK_TYPE"0402"
VALUE"22PF"
PART_NUMBER"TMP_QCH02206JB08"
CDS_LIB"pure_quanta"
LOCATION"C208"
$SEC"1"
CDS_SEC"1";
"B"
$PN"2"21;
"A"
$PN"1"32;
%"Q_CAP"
"1","(975,1100)","0","pure_quanta","I170";
;
VOLTAGE"50V"
VALUE"22PF"
TOLERANCE"5%"
MATERIAL"NPO"
PART_NUMBER"TMP_QCH02206JB08"
PACK_TYPE"0402"
CDS_LIB"pure_quanta"
LOCATION"C210"
$SEC"1"
CDS_SEC"1";
"B"
$PN"2"21;
"A"
$PN"1"31;
%"Q_RES"
"1","(-1675,2825)","0","pure_quanta","I19";
;
MATERIAL"CHIP"
VALUE"0"
PART_NUMBER"CS00002JB13"
PACK_TYPE"0402LF"
WATTAGE"1/16W"
CDS_LIB"pure_quanta"
TOLERANCE"5%"
LOCATION"R18"
$SEC"1"
CDS_SEC"1";
"B"
$PN"2"35;
"A"
$PN"1"7;
%"MOSFET_NCH_DUAL"
"2","(500,-725)","5","pure_quanta","I2";
;
VALUE"2N7002KDW"
PART_TYPE"SMLF"
MATERIAL"IC"
PART_NUMBER"BAM70020047"
CDS_LIB"pure_quanta"
CDS_LMAN_SYM_OUTLINE"-150,150,150,-150"
NEEDS_NO_SIZE"TRUE"
LOCATION"Q2"
$SEC"2"
CDS_SEC"2";
"S2"
$PN"4"45;
"G2"
$PN"5"34;
"D2"
$PN"3"44;
%"UNIVERSAL_POWER"
"1","(-1925,2946)","0","logical_power","I22";
;
HDL_POWER"P5V_AUX"
CDS_LIB"logical_power";
"A"7;
%"UNIVERSAL_GND"
"1","(-775,650)","0","logical_power","I24";
;
HDL_POWER"GND"
CDS_LIB"logical_power";
"A"18;
%"Q_CAP"
"1","(-1150,1075)","0","pure_quanta","I25";
;
VOLTAGE"50V"
MATERIAL"C0G"
TOLERANCE"5%"
PACK_TYPE"0402"
VALUE"15PF"
CDS_LIB"pure_quanta"
PART_NUMBER"CH01506JB06"
LOCATION"C205"
$SEC"1"
CDS_SEC"1";
"B"
$PN"2"18;
"A"
$PN"1"42;
%"Q_CAP"
"1","(-775,1075)","0","pure_quanta","I26";
;
MATERIAL"C0G"
TOLERANCE"5%"
VALUE"15PF"
VOLTAGE"50V"
PACK_TYPE"0402"
CDS_LIB"pure_quanta"
PART_NUMBER"CH01506JB06"
LOCATION"C206"
$SEC"1"
CDS_SEC"1";
"B"
$PN"2"18;
"A"
$PN"1"41;
%"Q_RES"
"2","(-1100,-200)","0","pure_quanta","I27";
;
TOLERANCE"1%"
PACK_TYPE"0402LF"
MATERIAL"CHIP"
WATTAGE"1/16W"
VALUE"4.7K"
PART_NUMBER"CS24702FB06"
CDS_LIB"pure_quanta"
LOCATION"R31"
$SEC"1"
CDS_SEC"1";
"A"
$PN"1"2;
"B"
$PN"2"55;
%"UNIVERSAL_POWER"
"1","(-1100,150)","0","logical_power","I28";
;
HDL_POWER"P3V3_RGM"
CDS_LIB"logical_power";
"A"2;
%"Q_CAP"
"1","(-425,1075)","0","pure_quanta","I29";
;
TOLERANCE"5%"
VOLTAGE"50V"
VALUE"15PF"
MATERIAL"C0G"
PACK_TYPE"0402"
CDS_LIB"pure_quanta"
PART_NUMBER"CH01506JB06"
LOCATION"C207"
$SEC"1"
CDS_SEC"1";
"B"
$PN"2"18;
"A"
$PN"1"37;
%"UNIVERSAL_GND"
"1","(-1475,2100)","0","logical_power","I31";
;
HDL_POWER"GND"
CDS_LIB"logical_power";
"A"19;
%"74HC1G126GW"
"1","(-625,2325)","0","pure_quanta","I32";
;
PART_TYPE"SMLF"
MATERIAL"IC"
VALUE"74HC1G126GW"
PART_NUMBER"AL1G0126007"
NEEDS_NO_SIZE"TRUE"
CDS_LMAN_SYM_OUTLINE"-100,100,100,-100"
CDS_LIB"pure_quanta"
LOCATION"U33"
$SEC"1"
CDS_SEC"1";
"GND"
$PN"3"19;
"1"
$PN"1"25;
"5"
$PN"5"35;
"4"
$PN"4"29;
"2"
$PN"2"38;
%"74HC1G126GW"
"1","(-1025,2725)","0","pure_quanta","I33";
;
PART_NUMBER"AL1G0126007"
VALUE"74HC1G126GW"
PART_TYPE"SMLF"
MATERIAL"IC"
NEEDS_NO_SIZE"TRUE"
CDS_LMAN_SYM_OUTLINE"-100,100,100,-100"
CDS_LIB"pure_quanta"
LOCATION"U26"
$SEC"1"
CDS_SEC"1";
"GND"
$PN"3"19;
"1"
$PN"1"25;
"5"
$PN"5"35;
"4"
$PN"4"24;
"2"
$PN"2"40;
%"Q_RES"
"1","(-925,3100)","0","pure_quanta","I34";
;
VALUE"33.2"
MATERIAL"CHIP"
TOLERANCE"1%"
PART_NUMBER"CS03322FB03"
PACK_TYPE"0402LF"
WATTAGE"1/16W"
CDS_LIB"pure_quanta"
LOCATION"R29"
$SEC"1"
CDS_SEC"1";
"B"
$PN"2"27;
"A"
$PN"1"39;
%"Q_RES"
"2","(-450,3475)","2","pure_quanta","I39";
;
PACK_TYPE"0402LF"
WATTAGE"1/16W"
MATERIAL"CHIP"
VALUE"0"
TOLERANCE"5%"
PART_NUMBER"CS00002JB13"
CDS_LIB"pure_quanta"
LOCATION"R30"
$SEC"1"
CDS_SEC"1";
"A"
$PN"1"10;
"B"
$PN"2"25;
%"Q_RES"
"1","(-1875,4075)","0","pure_quanta","I40";
;
PART_NUMBER"CS00003J910"
VALUE"0"
TOLERANCE"5%"
MATERIAL"EMPTY"
PACK_TYPE"0603LF"
WATTAGE"1/10W"
CDS_LIB"pure_quanta"
LOCATION"R27"
$SEC"1"
CDS_SEC"1";
"B"
$PN"2"8;
"A"
$PN"1"5;
%"SCHOTTKY_AC"
"1","(-1850,4275)","0","pure_quanta","I41";
;
PART_TYPE"SMLF"
VALUE"SS0530"
PART_NUMBER"BCSS0530Z00"
MATERIAL"IC"
NEEDS_NO_SIZE"TRUE"
CDS_LMAN_SYM_OUTLINE"-75,50,75,-50"
CDS_LIB"pure_quanta"
LOCATION"D11"
$SEC"1"
CDS_SEC"1";
"C"
$PN"C"8;
"A"
$PN"A"5;
%"SCHOTTKY_AC"
"1","(-1900,4675)","0","pure_quanta","I42";
;
PART_NUMBER"BCSS0530Z00"
VALUE"SS0530"
PART_TYPE"SMLF"
MATERIAL"EMPTY"
NEEDS_NO_SIZE"TRUE"
CDS_LMAN_SYM_OUTLINE"-75,50,75,-50"
CDS_LIB"pure_quanta"
LOCATION"D9"
$SEC"1"
CDS_SEC"1";
"C"
$PN"C"8;
"A"
$PN"A"5;
%"UNIVERSAL_GND"
"1","(-1425,3625)","0","logical_power","I44";
;
HDL_POWER"GND"
CDS_LIB"logical_power";
"A"20;
%"Q_CAP"
"1","(-1425,3875)","0","pure_quanta","I45";
;
VALUE"1UF"
MATERIAL"EMPTY"
PACK_TYPE"0603"
TOLERANCE"10%"
VOLTAGE"16V"
PART_NUMBER"TMP_QCH5103K1900"
CDS_LIB"pure_quanta"
LOCATION"C204"
$SEC"1"
CDS_SEC"1";
"B"
$PN"2"20;
"A"
$PN"1"8;
%"UNIVERSAL_POWER"
"1","(-1425,4825)","0","logical_power","I46";
;
HDL_POWER"CRT_VCC5"
CDS_LIB"logical_power";
"A"8;
%"UNIVERSAL_POWER"
"1","(-450,3700)","0","logical_power","I47";
;
HDL_POWER"CRT_VCC5"
CDS_LIB"logical_power";
"A"10;
%"Q_RES"
"2","(-800,-200)","0","pure_quanta","I50";
;
WATTAGE"1/16W"
MATERIAL"CHIP"
VALUE"4.7K"
PACK_TYPE"0402LF"
TOLERANCE"1%"
PART_NUMBER"CS24702FB06"
CDS_LIB"pure_quanta"
LOCATION"R32"
$SEC"1"
CDS_SEC"1";
"A"
$PN"1"2;
"B"
$PN"2"45;
%"Q_RES"
"1","(-350,-50)","0","pure_quanta","I51";
;
MATERIAL"CHIP"
VALUE"0"
PART_NUMBER"CS00002JB13"
PACK_TYPE"0402LF"
WATTAGE"1/16W"
CDS_LIB"pure_quanta"
TOLERANCE"5%"
LOCATION"R86"
$SEC"1"
CDS_SEC"1";
"B"
$PN"2"34;
"A"
$PN"1"3;
%"UNIVERSAL_POWER"
"1","(-575,100)","0","logical_power","I52";
;
HDL_POWER"P3V3_RGM"
CDS_LIB"logical_power";
"A"3;
%"UNIVERSAL_GND"
"1","(575,625)","0","logical_power","I53";
;
HDL_POWER"GND"
CDS_LIB"logical_power";
"A"21;
%"Q_CAP"
"1","(575,1100)","0","pure_quanta","I54";
;
VALUE"18PF"
TOLERANCE"5%"
PACK_TYPE"0402"
MATERIAL"C0G"
VOLTAGE"50V"
PART_NUMBER"CH01806JB07"
CDS_LIB"pure_quanta"
LOCATION"C209"
$SEC"1"
CDS_SEC"1";
"B"
$PN"2"21;
"A"
$PN"1"33;
%"MOSFET_NCH_DUAL"
"1","(150,-375)","5","pure_quanta","I56";
;
PART_NUMBER"BAM70020047"
MATERIAL"IC"
VALUE"2N7002KDW"
PART_TYPE"SMLF"
CDS_LIB"pure_quanta"
CDS_LMAN_SYM_OUTLINE"-150,150,150,-150"
NEEDS_NO_SIZE"TRUE"
LOCATION"Q2"
$SEC"1"
CDS_SEC"1";
"D1"
$PN"6"43;
"G1"
$PN"2"34;
"S1"
$PN"1"55;
%"Q_RES"
"2","(1450,1075)","0","pure_quanta","I57";
;
PACK_TYPE"0402LF"
MATERIAL"CHIP"
WATTAGE"1/16W"
TOLERANCE"1%"
VALUE"150"
PART_NUMBER"CS11502FB07"
CDS_LIB"pure_quanta"
LOCATION"R87"
$SEC"1"
CDS_SEC"1";
"A"
$PN"1"31;
"B"
$PN"2"22;
%"UNIVERSAL_GND"
"1","(2000,675)","0","logical_power","I58";
;
HDL_POWER"GND"
CDS_LIB"logical_power";
"A"22;
%"Q_RES"
"2","(2000,1100)","0","pure_quanta","I59";
;
PACK_TYPE"0402LF"
PART_NUMBER"CS11502FB07"
MATERIAL"CHIP"
VALUE"150"
TOLERANCE"1%"
WATTAGE"1/16W"
CDS_LIB"pure_quanta"
LOCATION"R88"
$SEC"1"
CDS_SEC"1";
"A"
$PN"1"33;
"B"
$PN"2"22;
%"Q_RES"
"1","(625,2325)","0","pure_quanta","I60";
;
VALUE"0"
MATERIAL"CHIP"
TOLERANCE"5%"
PACK_TYPE"0402LF"
WATTAGE"1/16W"
CDS_LIB"pure_quanta"
PART_NUMBER"CS00002JB13"
LOCATION"R85"
$SEC"1"
CDS_SEC"1";
"B"
$PN"2"28;
"A"
$PN"1"29;
%"Q_RES"
"1","(425,2725)","0","pure_quanta","I61";
;
VALUE"0"
TOLERANCE"5%"
MATERIAL"CHIP"
PACK_TYPE"0402LF"
WATTAGE"1/16W"
CDS_LIB"pure_quanta"
PART_NUMBER"CS00002JB13"
LOCATION"R84"
$SEC"1"
CDS_SEC"1";
"B"
$PN"2"30;
"A"
$PN"1"24;
%"Q_RES"
"2","(775,-200)","0","pure_quanta","I62";
;
WATTAGE"1/16W"
MATERIAL"CHIP"
PACK_TYPE"0402LF"
VALUE"2.2K"
TOLERANCE"5%"
PART_NUMBER"CS22202JB07"
CDS_LIB"pure_quanta"
LOCATION"R91"
$SEC"1"
CDS_SEC"1";
"A"
$PN"1"1;
"B"
$PN"2"43;
%"UNIVERSAL_POWER"
"1","(775,75)","0","logical_power","I63";
;
HDL_POWER"CRT_VCC5"
CDS_LIB"logical_power";
"A"1;
%"Q_RES"
"2","(1025,-200)","0","pure_quanta","I64";
;
TOLERANCE"5%"
WATTAGE"1/16W"
VALUE"2.2K"
MATERIAL"CHIP"
PACK_TYPE"0402LF"
PART_NUMBER"CS22202JB07"
CDS_LIB"pure_quanta"
LOCATION"R92"
$SEC"1"
CDS_SEC"1";
"A"
$PN"1"1;
"B"
$PN"2"44;
%"Q_RES"
"2","(2525,1100)","0","pure_quanta","I65";
;
TOLERANCE"1%"
WATTAGE"1/16W"
MATERIAL"CHIP"
PART_NUMBER"CS11502FB07"
PACK_TYPE"0402LF"
VALUE"150"
CDS_LIB"pure_quanta"
LOCATION"R89"
$SEC"1"
CDS_SEC"1";
"A"
$PN"1"32;
"B"
$PN"2"22;
%"Q_CAP"
"1","(4750,700)","0","pure_quanta","I67";
;
TOLERANCE"1%"
PACK_TYPE"0402"
VOLTAGE"50V"
VALUE"10PF"
MATERIAL"NPO"
PART_NUMBER"TMP_QCH0106F0B00"
CDS_LIB"pure_quanta"
LOCATION"C211"
$SEC"1"
CDS_SEC"1";
"B"
$PN"2"16;
"A"
$PN"1"28;
%"Q_RES"
"1","(4750,3425)","0","pure_quanta","I68";
;
VALUE"2.21K"
MATERIAL"EMPTY"
TOLERANCE"1%"
PART_NUMBER"CS22212FB06"
PACK_TYPE"0402LF"
WATTAGE"1/16W"
CDS_LIB"pure_quanta"
LOCATION"R17"
$SEC"1"
CDS_SEC"1";
"B"
$PN"2"11;
"A"
$PN"1"27;
%"UNIVERSAL_POWER"
"1","(5625,4850)","0","logical_power","I71";
;
HDL_POWER"CRT_VCC5"
CDS_LIB"logical_power";
"A"4;
%"UNIVERSAL_GND"
"1","(6075,3700)","0","logical_power","I73";
;
CDS_LIB"logical_power"
HDL_POWER"GND";
"A"15;
%"BZA462A"
"1","(6200,4200)","3","pure_quanta","I74";
;
MATERIAL"EMPTY"
PART_NUMBER"BCZA462AZ01"
VALUE"BZA462A"
PART_TYPE"SMLF"
NEEDS_NO_SIZE"TRUE"
CDS_LMAN_SYM_OUTLINE"-250,475,250,-475"
CDS_LIB"pure_quanta"
LOCATION"D12"
$SEC"1"
CDS_SEC"1";
"6"
$PN"6"4;
"4"
$PN"4"4;
"3"
$PN"3"4;
"1"
$PN"1"4;
"5"
$PN"5"14;
"2"
$PN"2"15;
%"Q_RES"
"1","(4875,3575)","0","pure_quanta","I75";
;
VALUE"2.21K"
MATERIAL"EMPTY"
CDS_LIB"pure_quanta"
WATTAGE"1/16W"
PACK_TYPE"0402LF"
PART_NUMBER"CS22212FB06"
TOLERANCE"1%"
LOCATION"R16"
$SEC"1"
CDS_SEC"1";
"B"
$PN"2"11;
"A"
$PN"1"36;
%"UNIVERSAL_GND"
"1","(6325,3700)","0","logical_power","I76";
;
CDS_LIB"logical_power"
HDL_POWER"GND";
"A"14;
%"Q_CAP"
"1","(5200,700)","0","pure_quanta","I77";
;
TOLERANCE"1%"
VOLTAGE"50V"
VALUE"10PF"
PACK_TYPE"0402"
MATERIAL"NPO"
PART_NUMBER"TMP_QCH0106F0B00"
CDS_LIB"pure_quanta"
LOCATION"C212"
$SEC"1"
CDS_SEC"1";
"B"
$PN"2"16;
"A"
$PN"1"30;
%"UNIVERSAL_GND"
"1","(6000,250)","0","logical_power","I82";
;
CDS_LIB"logical_power"
HDL_POWER"GND";
"A"16;
%"Q_CAP"
"1","(5600,700)","0","pure_quanta","I83";
;
MATERIAL"EMPTY"
PACK_TYPE"0402"
TOLERANCE"5%"
VALUE"100PF"
VOLTAGE"50V"
CDS_LIB"pure_quanta"
PART_NUMBER"CH11006JB18"
LOCATION"C213"
$SEC"1"
CDS_SEC"1";
"B"
$PN"2"16;
"A"
$PN"1"27;
%"Q_CAP"
"1","(6000,700)","0","pure_quanta","I84";
;
PACK_TYPE"0402"
MATERIAL"EMPTY"
TOLERANCE"5%"
VOLTAGE"50V"
VALUE"100PF"
CDS_LIB"pure_quanta"
PART_NUMBER"CH11006JB18"
LOCATION"C214"
$SEC"1"
CDS_SEC"1";
"B"
$PN"2"16;
"A"
$PN"1"36;
%"UNIVERSAL_POWER"
"1","(5350,3775)","0","logical_power","I97";
;
HDL_POWER"CRT_VCC5"
CDS_LIB"logical_power";
"A"11;
%"UNIVERSAL_POWER"
"1","(-2175,4825)","0","logical_power","I98";
;
HDL_POWER"P5V_AUX"
CDS_LIB"logical_power";
"A"5;
%"Q_RES"
"1","(-925,3300)","0","pure_quanta","I99";
;
MATERIAL"CHIP"
VALUE"33.2"
TOLERANCE"1%"
PART_NUMBER"CS03322FB03"
PACK_TYPE"0402LF"
WATTAGE"1/16W"
CDS_LIB"pure_quanta"
LOCATION"R28"
$SEC"1"
CDS_SEC"1";
"B"
$PN"2"36;
"A"
$PN"1"26;
END.
